# T6G (Grand Teton) — schematic parts with pin connectivity, parts 3899–4046 of 8303; source: Cadence DE-HDL packaged netlist (pstxprt.dat, pstxnet.dat, pstchip.dat)

PQ17  MOSFET_N  BSS138K IC  pkg SMLF  page 193
  D  DRAIN  OUT  = PVDDCR_SOC_P0_EN_GD
  G  GATE  IN  = PVDDCR_SOC_P0_EN_RC
  S  SOURCE  BI  = GND

PR3  Q_RES  10K 1% CHIP  pkg 0402LF  page 207 : 1 = PVDD11_S3_P0_VMON ; 2 = GND
PR4  Q_RES  10K 1% CHIP  pkg 0402LF  page 210 : 1 = PVDDCR_CPU0_P1_VMON ; 2 = GND
PR5  Q_RES  10K 1% CHIP  pkg 0402LF  page 193 : 1 = PVDDCR_CPU0_P0_VMON ; 2 = GND
PR6  Q_RES  10K 1% CHIP  pkg 0402LF  page 224 : 1 = PVDD11_S3_P1_VMON ; 2 = GND
PR7  Q_RES  8.87K 1% EMPTY  pkg 0402LF  page 203 : 1 = PVDDCR_CPU1_P0_LSET6 ; 2 = GND
PR8  Q_RES  8.66K 1% CHIP  pkg 0402LF  page 226 : 1 = PVDD18_S5_P1_CS ; 2 = GND
PR12  Q_RES  0 5% CHIP  pkg 0402LF  page 217 : 1 = NC_PVDDCR_CPU1_P1_IMON8 ; 2 = GND
PR13  Q_RES  0 5% CHIP  pkg 0402LF  page 224 : 1 = NC_PVDD11_S3_P1_IMON5 ; 2 = GND
PR14  Q_RES  0 5% CHIP  pkg 0402LF  page 224 : 1 = NC_PVDD11_S3_P1_IMON6 ; 2 = GND
PR32  Q_RES  0 5% CHIP  pkg 0402LF  page 200 : 1 = NC_PVDDCR_CPU1_P0_IMON8 ; 2 = GND
PR33  Q_RES  0 5% CHIP  pkg 0402LF  page 207 : 1 = NC_PVDD11_S3_P0_IMON4 ; 2 = GND
PR34  Q_RES  0 5% CHIP  pkg 0402LF  page 207 : 1 = NC_PVDD11_S3_P0_IMON5 ; 2 = GND
PR35  Q_RES  0 5% CHIP  pkg 0402LF  page 207 : 1 = NC_PVDD11_S3_P0_IMON6 ; 2 = GND
PR36  Q_RES  0 5% CHIP  pkg 0402LF  page 207 : 1 = NC_PVDD11_S3_P0_IMON8 ; 2 = GND
PR37  Q_RES  0 5% CHIP  pkg 0402LF  page 207 : 1 = NC_PVDD11_S3_P0_IMON3 ; 2 = GND
PR40  Q_RES  0 5% CHIP  pkg 0402LF  page 200 : 1 = SVID_PVDDCR_CPU1_P0_SVTI ; 2 = GND
PR41  Q_RES  1K 1% EMPTY  pkg 0402LF  page 200 : 1 = PVDD18_S5_P0 ; 2 = SVID_PVDDCR_CPU1_P0_SVTI
PR46  Q_RES  1.5 1% EMPTY  pkg 0402LF  page 213 : 1 = SW_PVDDCR_CPU0_P1_SW5_RC ; 2 = GND
PR49  Q_RES  49.9 1% CHIP  pkg 0402LF  page 200 : 1 = VSENSE_VSS_SENSE_C_P0 ; 2 = GND
PR50  Q_RES  49.9 1% CHIP  pkg 0402LF  page 200 : 1 = VSENSE_VSS_SENSE_B_P0 ; 2 = GND
PR51  Q_RES  49.9 1% CHIP  pkg 0402LF  page 200 : 1 = VSENSE_PVDDCR_CPU1_P0_DP ; 2 = PVDDCR_CPU1_P0
PR52  Q_RES  49.9 1% CHIP  pkg 0402LF  page 200 : 1 = VSENSE_PVDDIO_P0_DP ; 2 = PVDDIO_P0
PR53  Q_RES  40.2K 1% CHIP  pkg 0402LF  page 200 : 1 = P5V_AUX ; 2 = PVDDCR_CPU1_P0_VMON
PR54  Q_RES  10K 1% CHIP  pkg 0402LF  page 200 : 1 = PVDDCR_CPU1_P0_VMON ; 2 = GND
PR55  Q_RES  1K 1% CHIP  pkg 0402LF  page 200 : 1 = P3V3_AUX ; 2 = PVDDIO_P0_EN_G
PR59  Q_RES  0 5% CHIP  pkg 0402LF  page 27 : 1 = SVID_PVDDCR_CPU1_P0_SVC_R ; 2 = SVID_PVDDCR_CPU1_P0_SVC
PR60  Q_RES  0 5% CHIP  pkg 0402LF  page 27 : 1 = SVID_PVDDCR_CPU1_P0_SVD_R ; 2 = SVID_PVDDCR_CPU1_P0_SVD
PR62  Q_RES  0 5% CHIP  pkg 0402LF  page 200 : 1 = SVID_PVDDCR_CPU1_P0_SVTI ; 2 = SVID_PVDDCR_CPU1_P0_SVTI_R
PR67  Q_RES  1.96K 1% CHIP  pkg 0402LF  page 200 : 1 = PVDDCR_CPU1_P0_EN1_ADDR_CFG ; 2 = GND
PR68  Q_RES  0 5% CHIP  pkg 0402LF  page 200 : 1 = VSENSE_PVDDCR_CPU1_P0_DP ; 2 = VSENSE_PVDDCR_CPU1_P0_VSEN0
PR69  Q_RES  0 5% CHIP  pkg 0402LF  page 200 : 1 = VSENSE_PVDDIO_P0_DP ; 2 = VSENSE_PVDDIO_P0_VSEN1
PR74  Q_RES  0 5% CHIP  pkg 0402LF  page 200 : 1 = P12V_AUX ; 2 = PVDDCR_CPU1_P0_VINSEN
PR76  Q_RES  1 1% CHIP  pkg 0402LF  page 200 : 1 = PVDDCR_CPU1_P0_VCC ; 2 = P3V3_AUX
PR77  Q_RES  8.87K 1% EMPTY  pkg 0402LF  page 201 : 1 = PVDDCR_CPU1_P0_LSET2 ; 2 = GND
PR78  Q_RES  8.87K 1% EMPTY  pkg 0402LF  page 201 : 1 = PVDDCR_CPU1_P0_LSET1 ; 2 = GND
PR79  Q_RES  2.2 1% CHIP  pkg 0402LF  page 201 : 1 = PVDDCR_CPU1_P0_PVCC ; 2 = PVDDCR_CPU1_P0_VCC1
PR80  Q_RES  2.2 1% CHIP  pkg 0402LF  page 201 : 1 = PVDDCR_CPU1_P0_PVCC ; 2 = PVDDCR_CPU1_P0_VCC2
PR81  Q_RES  5.6 1% CHIP  pkg 0402LF  page 201 : 1 = SW_PVDDCR_CPU1_P0_BOOT2 ; 2 = SW_PVDDCR_CPU1_P0_BOOT2_R
PR82  Q_RES  5.6 1% CHIP  pkg 0402LF  page 201 : 1 = SW_PVDDCR_CPU1_P0_BOOT1 ; 2 = SW_PVDDCR_CPU1_P0_BOOT1_R
PR83  Q_RES  0 5% CHIP  pkg 0402LF  page 201 : 1 = PVDDCR_CPU1_P0_VOS2 ; 2 = PVDDCR_CPU1_P0
PR84  Q_RES  0 5% CHIP  pkg 0402LF  page 201 : 1 = PVDDCR_CPU1_P0_VOS1 ; 2 = PVDDCR_CPU1_P0
PR85  Q_RES  8.87K 1% EMPTY  pkg 0402LF  page 202 : 1 = PVDDCR_CPU1_P0_LSET4 ; 2 = GND
PR86  Q_RES  8.87K 1% EMPTY  pkg 0402LF  page 202 : 1 = PVDDCR_CPU1_P0_LSET3 ; 2 = GND
PR87  Q_RES  2.2 1% CHIP  pkg 0402LF  page 202 : 1 = PVDDCR_CPU1_P0_PVCC ; 2 = PVDDCR_CPU1_P0_VCC4
PR88  Q_RES  2.2 1% CHIP  pkg 0402LF  page 202 : 1 = PVDDCR_CPU1_P0_PVCC ; 2 = PVDDCR_CPU1_P0_VCC3
PR89  Q_RES  5.6 1% CHIP  pkg 0402LF  page 202 : 1 = SW_PVDDCR_CPU1_P0_BOOT4 ; 2 = SW_PVDDCR_CPU1_P0_BOOT4_R
PR90  Q_RES  5.6 1% CHIP  pkg 0402LF  page 202 : 1 = SW_PVDDCR_CPU1_P0_BOOT3 ; 2 = SW_PVDDCR_CPU1_P0_BOOT3_R
PR91  Q_RES  0 5% CHIP  pkg 0402LF  page 202 : 1 = PVDDCR_CPU1_P0_VOS4 ; 2 = PVDDCR_CPU1_P0
PR92  Q_RES  0 5% CHIP  pkg 0402LF  page 202 : 1 = PVDDCR_CPU1_P0_VOS3 ; 2 = PVDDCR_CPU1_P0
PR93  Q_RES  8.87K 1% EMPTY  pkg 0402LF  page 203 : 1 = PVDDCR_CPU1_P0_LSET5 ; 2 = GND
PR94  Q_RES  2.2 1% CHIP  pkg 0402LF  page 203 : 1 = PVDDCR_CPU1_P0_PVCC ; 2 = PVDDCR_CPU1_P0_VCC5
PR95  Q_RES  5.6 1% CHIP  pkg 0402LF  page 203 : 1 = SW_PVDDCR_CPU1_P0_BOOT5 ; 2 = SW_PVDDCR_CPU1_P0_BOOT5_R
PR96  Q_RES  0 5% CHIP  pkg 0402LF  page 203 : 1 = PVDDCR_CPU1_P0_VOS5 ; 2 = PVDDCR_CPU1_P0
PR97  Q_RES  8.87K 1% EMPTY  pkg 0402LF  page 205 : 1 = PVDDIO_P0_LSET2 ; 2 = GND
PR98  Q_RES  8.87K 1% EMPTY  pkg 0402LF  page 205 : 1 = PVDDIO_P0_LSET1 ; 2 = GND
PR99  Q_RES  2.2 1% CHIP  pkg 0402LF  page 205 : 1 = PVDDCR_CPU1_P0_PVCC ; 2 = PVDDIO_P0_VCC2
PR100  Q_RES  2.2 1% CHIP  pkg 0402LF  page 205 : 1 = PVDDCR_CPU1_P0_PVCC ; 2 = PVDDIO_P0_VCC1
PR101  Q_RES  5.6 1% CHIP  pkg 0402LF  page 205 : 1 = SW_PVDDIO_P0_BOOT1 ; 2 = SW_PVDDIO_P0_BOOT1_R
PR102  Q_RES  5.6 1% CHIP  pkg 0402LF  page 205 : 1 = SW_PVDDIO_P0_BOOT2 ; 2 = SW_PVDDIO_P0_BOOT2_R
PR103  Q_RES  0 5% CHIP  pkg 0402LF  page 205 : 1 = PVDDIO_P0_VOS1 ; 2 = PVDDIO_P0
PR104  Q_RES  0 5% CHIP  pkg 0402LF  page 205 : 1 = PVDDIO_P0_VOS2 ; 2 = PVDDIO_P0
PR105  Q_RES  8.87K 1% EMPTY  pkg 0402LF  page 206 : 1 = PVDDIO_P0_LSET4 ; 2 = GND
PR106  Q_RES  8.87K 1% EMPTY  pkg 0402LF  page 206 : 1 = PVDDIO_P0_LSET3 ; 2 = GND
PR107  Q_RES  2.2 1% CHIP  pkg 0402LF  page 206 : 1 = PVDDCR_CPU1_P0_PVCC ; 2 = PVDDIO_P0_VCC4
PR108  Q_RES  2.2 1% CHIP  pkg 0402LF  page 206 : 1 = PVDDCR_CPU1_P0_PVCC ; 2 = PVDDIO_P0_VCC3
PR109  Q_RES  5.6 1% CHIP  pkg 0402LF  page 206 : 1 = SW_PVDDIO_P0_BOOT4 ; 2 = SW_PVDDIO_P0_BOOT4_R
PR110  Q_RES  5.6 1% CHIP  pkg 0402LF  page 206 : 1 = SW_PVDDIO_P0_BOOT3 ; 2 = SW_PVDDIO_P0_BOOT3_R
PR111  Q_RES  0 5% CHIP  pkg 0402LF  page 206 : 1 = PVDDIO_P0_VOS3 ; 2 = PVDDIO_P0
PR112  Q_RES  0 5% CHIP  pkg 0402LF  page 206 : 1 = PVDDIO_P0_VOS4 ; 2 = PVDDIO_P0
PR113  Q_RES  40.2K 1% CHIP  pkg 0402LF  page 207 : 1 = P5V_AUX ; 2 = PVDD11_S3_P0_VMON
PR114  Q_RES  49.9 1% CHIP  pkg 0402LF  page 207 : 1 = PVDD11_S3_P0 ; 2 = VSENSE_PVDD11_S3_P0_DP
PR115  Q_RES  49.9 1% CHIP  pkg 0402LF  page 207 : 1 = VSENSE_VSS_SENSE_C_P0 ; 2 = GND
PR121  Q_RES  0 5% CHIP  pkg 0402LF  page 207 : 1 = VSENSE_PVDD11_S3_P0_DP ; 2 = VSENSE_PVDD11_S3_P0_R
PR125  Q_RES  0 5% CHIP  pkg 0402LF  page 207 : 1 = P12V_AUX ; 2 = PVDD11_S3_P0_VINSEN
PR126  Q_RES  3.09K 1% CHIP  pkg 0402LF  page 207 : 1 = PVDD11_S3_P0_ADDR_CFG ; 2 = GND
PR127  Q_RES  0 5% EMPTY  pkg 0402LF  page 207 : 1 = PVDD11_S3_P0_RESET_N_R ; 2 = GND
PR128  Q_RES  1K 1% EMPTY  pkg 0402LF  page 207 : 1 = PVDD11_S3_P0_RESET_N_R ; 2 = PVDD18_S5_P0
PR129  Q_RES  0 5% EMPTY  pkg 0402LF  page 207 : 1 = PVDD11_S3_P0_RESET_N_R ; 2 = PVDD11_S3_P0_RESET_N
PR130  Q_RES  1 1% CHIP  pkg 0402LF  page 207 : 1 = PVDD11_S3_P0_VCC ; 2 = P3V3_AUX
PR131  Q_RES  2.2 1% CHIP  pkg 0402LF  page 208 : 1 = PVDD11_S3_P0_PVCC ; 2 = PVDD11_S3_P0_VCC1
PR132  Q_RES  2.2 1% CHIP  pkg 0402LF  page 208 : 1 = PVDD11_S3_P0_PVCC ; 2 = PVDD11_S3_P0_VCC2
PR133  Q_RES  4.87K 1% EMPTY  pkg 0402LF  page 208 : 1 = GND ; 2 = PVDD11_S3_P0_LSET1
PR134  Q_RES  4.87K 1% EMPTY  pkg 0402LF  page 208 : 1 = GND ; 2 = PVDD11_S3_P0_LSET2
PR135  Q_RES  5.6 1% CHIP  pkg 0402LF  page 208 : 1 = SW_PVDD11_S3_P0_BOOT1 ; 2 = SW_PVDD11_S3_P0_BOOT1_RC
PR136  Q_RES  5.6 1% CHIP  pkg 0402LF  page 208 : 1 = SW_PVDD11_S3_P0_BOOT2 ; 2 = SW_PVDD11_S3_P0_BOOT2_RC
PR137  Q_RES  0 5% CHIP  pkg 0402LF  page 208 : 1 = PVDD11_S3_P0_VOS1 ; 2 = PVDD11_S3_P0
PR138  Q_RES  0 5% CHIP  pkg 0402LF  page 208 : 1 = PVDD11_S3_P0_VOS2 ; 2 = PVDD11_S3_P0
PR147  Q_RES  10K 1% CHIP  pkg 0402LF  page 226 : 1 = PVDD18_S5_P1_FB ; 2 = PVDD18_SS_P1_RGND
PR148  Q_RES  20K 1% CHIP  pkg 0402LF  page 226 : 1 = PVDD18_S5_P1_FB ; 2 = PVDD18_S5_P1_FB_RC
PR150  Q_RES  0 5% CHIP  pkg 0402LF  page 210 : 1 = SVID_PVDDCR_CPU0_P1_SVTI ; 2 = GND
PR151  Q_RES  1K 1% EMPTY  pkg 0402LF  page 210 : 1 = PVDD18_S5_P1 ; 2 = SVID_PVDDCR_CPU0_P1_SVTI
PR152  Q_RES  1K 1% CHIP  pkg 0402LF  page 210 : 1 = P3V3_AUX ; 2 = PVDDCR_SOC_P1_EN_GD
PR155  Q_RES  1.5 1% EMPTY  pkg 0402LF  page 203 : 1 = SW_PVDDCR_CPU1_P0_SW6_RC ; 2 = GND
PR157  Q_RES  40.2K 1% CHIP  pkg 0402LF  page 210 : 1 = P5V_AUX ; 2 = PVDDCR_CPU0_P1_VMON
PR158  Q_RES  1.5 1% EMPTY  pkg 0402LF  page 203 : 1 = SW_PVDDCR_CPU1_P0_SW5_RC ; 2 = GND
PR159  Q_RES  5.23K 1% CHIP  pkg 0402LF  page 210 : 1 = PVDDCR_SOC_P1_EN//ADDR_CFG ; 2 = GND
PR161  Q_RES  49.9 1% CHIP  pkg 0402LF  page 210 : 1 = PVDDCR_CPU0_P1 ; 2 = VSENSE_PVDDCR_CPU0_P1_DP
PR162  Q_RES  49.9 1% CHIP  pkg 0402LF  page 210 : 1 = VSENSE_VSS_SENSE_A_P1 ; 2 = GND
PR163  Q_RES  49.9 1% CHIP  pkg 0402LF  page 210 : 1 = PVDDCR_SOC_P1 ; 2 = VSENSE_PVDDCR_SOC_P1_DP
PR164  Q_RES  49.9 1% CHIP  pkg 0402LF  page 210 : 1 = VSENSE_VSS_SENSE_A_P1 ; 2 = GND
PR169  Q_RES  0 5% CHIP  pkg 0402LF  page 54 : 1 = SVID_PVDDCR_CPU0_P1_SVC_R ; 2 = SVID_PVDDCR_CPU0_P1_SVC
PR170  Q_RES  0 5% CHIP  pkg 0402LF  page 54 : 1 = SVID_PVDDCR_CPU0_P1_SVD_R ; 2 = SVID_PVDDCR_CPU0_P1_SVD
PR172  Q_RES  0 5% CHIP  pkg 0402LF  page 210 : 1 = SVID_PVDDCR_CPU0_P1_SVTI ; 2 = SVID_PVDDCR_CPU0_P1_SVTI_R
PR173  Q_RES  0 5% CHIP  pkg 0402LF  page 210 : 1 = VSENSE_PVDDCR_CPU0_P1_DP ; 2 = VSENSE_PVDDCR_CPU0_P1_VSEN0
PR174  Q_RES  0 5% CHIP  pkg 0402LF  page 210 : 1 = VSENSE_PVDDCR_SOC_P1_DP ; 2 = VSENSE_PVDDCR_SOC_P1_VSEN1
PR181  Q_RES  0 5% CHIP  pkg 0402LF  page 210 : 1 = P12V_AUX ; 2 = PVDDCR_CPU0_P1_VINSEN
PR183  Q_RES  1 1% CHIP  pkg 0402LF  page 210 : 1 = PVDDCR_CPU0_P1_VCC ; 2 = P3V3_AUX
PR185  Q_RES  2.2 1% CHIP  pkg 0402LF  page 211 : 1 = PVDDCR_CPU0_P1_PVCC ; 2 = PVDDCR_CPU0_P1_VCC1
PR186  Q_RES  2.2 1% CHIP  pkg 0402LF  page 211 : 1 = PVDDCR_CPU0_P1_PVCC ; 2 = PVDDCR_CPU0_P1_VCC2
PR187  Q_RES  8.87K 1% EMPTY  pkg 0402LF  page 211 : 1 = GND ; 2 = PVDDCR_CPU0_P1_LSET1
PR188  Q_RES  8.87K 1% EMPTY  pkg 0402LF  page 211 : 1 = GND ; 2 = PVDDCR_CPU0_P1_LSET2
PR189  Q_RES  5.6 1% CHIP  pkg 0402LF  page 211 : 1 = SW_PVDDCR_CPU0_P1_BOOT1 ; 2 = SW_PVDDCR_CPU0_P1_BOOT1_RC
PR190  Q_RES  5.6 1% CHIP  pkg 0402LF  page 211 : 1 = SW_PVDDCR_CPU0_P1_BOOT2 ; 2 = SW_PVDDCR_CPU0_P1_BOOT2_RC
PR191  Q_RES  0 5% CHIP  pkg 0402LF  page 211 : 1 = PVDDCR_CPU0_P1_VOS1 ; 2 = PVDDCR_CPU0_P1
PR192  Q_RES  0 5% CHIP  pkg 0402LF  page 211 : 1 = PVDDCR_CPU0_P1_VOS2 ; 2 = PVDDCR_CPU0_P1
PR193  Q_RES  2.2 1% CHIP  pkg 0402LF  page 212 : 1 = PVDDCR_CPU0_P1_PVCC ; 2 = PVDDCR_CPU0_P1_VCC3
PR194  Q_RES  2.2 1% CHIP  pkg 0402LF  page 212 : 1 = PVDDCR_CPU0_P1_PVCC ; 2 = PVDDCR_CPU0_P1_VCC4
PR195  Q_RES  8.87K 1% EMPTY  pkg 0402LF  page 212 : 1 = GND ; 2 = PVDDCR_CPU0_P1_LSET3
PR196  Q_RES  8.87K 1% EMPTY  pkg 0402LF  page 212 : 1 = GND ; 2 = PVDDCR_CPU0_P1_LSET4
PR197  Q_RES  5.6 1% CHIP  pkg 0402LF  page 212 : 1 = SW_PVDDCR_CPU0_P1_BOOT3 ; 2 = SW_PVDDCR_CPU0_P1_BOOT3_RC
PR198  Q_RES  5.6 1% CHIP  pkg 0402LF  page 212 : 1 = SW_PVDDCR_CPU0_P1_BOOT4 ; 2 = SW_PVDDCR_CPU0_P1_BOOT4_RC
PR199  Q_RES  0 5% CHIP  pkg 0402LF  page 212 : 1 = PVDDCR_CPU0_P1_VOS3 ; 2 = PVDDCR_CPU0_P1
PR200  Q_RES  0 5% CHIP  pkg 0402LF  page 212 : 1 = PVDDCR_CPU0_P1_VOS4 ; 2 = PVDDCR_CPU0_P1
PR201  Q_RES  2.2 1% CHIP  pkg 0402LF  page 213 : 1 = PVDDCR_CPU0_P1_PVCC ; 2 = PVDDCR_CPU0_P1_VCC5
PR202  Q_RES  8.87K 1% EMPTY  pkg 0402LF  page 213 : 1 = GND ; 2 = PVDDCR_CPU0_P1_LSET5
PR203  Q_RES  5.6 1% CHIP  pkg 0402LF  page 213 : 1 = SW_PVDDCR_CPU0_P1_BOOT5 ; 2 = SW_PVDDCR_CPU0_P1_BOOT5_RC
PR204  Q_RES  0 5% CHIP  pkg 0402LF  page 213 : 1 = PVDDCR_CPU0_P1_VOS5 ; 2 = PVDDCR_CPU0_P1
PR205  Q_RES  2.2 1% CHIP  pkg 0402LF  page 215 : 1 = PVDDCR_CPU0_P1_PVCC ; 2 = PVDDCR_SOC_P1_VCC1
PR206  Q_RES  2.2 1% CHIP  pkg 0402LF  page 215 : 1 = PVDDCR_CPU0_P1_PVCC ; 2 = PVDDCR_SOC_P1_VCC2
PR207  Q_RES  8.87K 1% EMPTY  pkg 0402LF  page 215 : 1 = GND ; 2 = PVDDCR_SOC_P1_LSET1
PR208  Q_RES  8.87K 1% EMPTY  pkg 0402LF  page 215 : 1 = GND ; 2 = PVDDCR_SOC_P1_LSET2
PR209  Q_RES  5.6 1% CHIP  pkg 0402LF  page 215 : 1 = SW_PVDDCR_SOC_P1_BOOT1 ; 2 = SW_PVDDCR_SOC_P1_BOOT1_RC
PR210  Q_RES  5.6 1% CHIP  pkg 0402LF  page 215 : 1 = SW_PVDDCR_SOC_P1_BOOT2 ; 2 = SW_PVDDCR_SOC_P1_BOOT2_RC
PR211  Q_RES  0 5% CHIP  pkg 0402LF  page 215 : 1 = PVDDCR_SOC_P1_VOS1 ; 2 = PVDDCR_SOC_P1
PR212  Q_RES  0 5% CHIP  pkg 0402LF  page 215 : 1 = PVDDCR_SOC_P1_VOS2 ; 2 = PVDDCR_SOC_P1
PR213  Q_RES  2.2 1% CHIP  pkg 0402LF  page 216 : 1 = PVDDCR_CPU0_P1_PVCC ; 2 = PVDDCR_SOC_P1_VCC3
PR214  Q_RES  8.87K 1% EMPTY  pkg 0402LF  page 216 : 1 = GND ; 2 = PVDDCR_SOC_P1_LSET3
PR215  Q_RES  5.6 1% CHIP  pkg 0402LF  page 216 : 1 = SW_PVDDCR_SOC_P1_BOOT3 ; 2 = SW_PVDDCR_SOC_P1_BOOT3_RC
PR216  Q_RES  0 5% CHIP  pkg 0402LF  page 216 : 1 = PVDDCR_SOC_P1_VOS3 ; 2 = PVDDCR_SOC_P1
PR217  Q_RES  0 5% CHIP  pkg 0402LF  page 217 : 1 = SVID_PVDDCR_CPU1_P1_SVTI ; 2 = GND
PR218  Q_RES  1K 1% EMPTY  pkg 0402LF  page 217 : 1 = PVDD18_S5_P1 ; 2 = SVID_PVDDCR_CPU1_P1_SVTI
PR221  Q_RES  1.5 1% EMPTY  pkg 0402LF  page 205 : 1 = SW_PVDDIO_P0_SW1_RC ; 2 = GND
PR223  Q_RES  1.5 1% EMPTY  pkg 0402LF  page 205 : 1 = SW_PVDDIO_P0_SW2_RC ; 2 = GND
PR226  Q_RES  49.9 1% CHIP  pkg 0402LF  page 217 : 1 = VSENSE_VSS_SENSE_C_P1 ; 2 = GND
PR227  Q_RES  49.9 1% CHIP  pkg 0402LF  page 217 : 1 = VSENSE_PVDDIO_P1_DP ; 2 = PVDDIO_P1
PR228  Q_RES  49.9 1% CHIP  pkg 0402LF  page 217 : 1 = VSENSE_PVDDCR_CPU1_P1_DP ; 2 = PVDDCR_CPU1_P1
PR229  Q_RES  49.9 1% CHIP  pkg 0402LF  page 224 : 1 = PVDD11_S3_P1 ; 2 = VSENSE_PVDD11_S3_P1_DP
